(kicad_pcb
	(version 20260206)
	(generator "pcbnew")
	(generator_version "10.0")
	(general
		(thickness 1.6)
		(legacy_teardrops no)
	)
	(paper "A4")
	(title_block
		(title "Bryce Canyon_F.DPB_16315-1-OCP.brd")
		(comment 1 "Bryce Canyon / footprints 875-879 of 2223")
	)
	(layers
		(0 "F.Cu" signal "TOP")
		(4 "In1.Cu" signal "L2GND")
		(6 "In2.Cu" signal "L3")
		(8 "In3.Cu" signal "L4GND")
		(10 "In4.Cu" signal "L5")
		(12 "In5.Cu" signal "L6VCC")
		(14 "In6.Cu" signal "L7VCC")
		(16 "In7.Cu" signal "L8")
		(18 "In8.Cu" signal "L9GND")
		(20 "In9.Cu" signal "L10")
		(22 "In10.Cu" signal "L11GND")
		(2 "B.Cu" signal "BOTTOM")
		(9 "F.Adhes" user "F.Adhesive")
		(11 "B.Adhes" user "B.Adhesive")
		(13 "F.Paste" user "Package Geometry/Pastemask Top")
		(15 "B.Paste" user "Package Geometry/Pastemask Bottom")
		(5 "F.SilkS" user "Ref Des/Silkscreen Top")
		(7 "B.SilkS" user "Ref Des/Silkscreen Bottom")
		(1 "F.Mask" user "Board Geometry/Soldermask Top")
		(3 "B.Mask" user "Board Geometry/Soldermask Bottom")
		(17 "Dwgs.User" user "User.Drawings")
		(19 "Cmts.User" user "User.Comments")
		(21 "Eco1.User" user "User.Eco1")
		(23 "Eco2.User" user "User.Eco2")
		(25 "Edge.Cuts" user "Board Geometry/Outline")
		(27 "Margin" user)
		(31 "F.CrtYd" user "Package Geometry/Place Bound Top")
		(29 "B.CrtYd" user "Package Geometry/Place Bound Bottom")
		(35 "F.Fab" user "Ref Des/Assembly Top")
		(33 "B.Fab" user "Ref Des/Assembly Bottom")
	)
	(footprint ""
		(layer "F.Cu")
		(at 219.907866 -15.20698 -90)
		(property "Reference" "TC4"
			(at 0 0 270)
			(layer "F.SilkS")
			(hide yes)
			(effects
				(font
					(size 1.27 1.27)
				)
			)
		)
		(property "Value" "ST100U16VDM-3-GP"
			(at 0 -9.6012 270)
			(unlocked yes)
			(layer "F.Fab")
			(hide yes)
			(effects
				(font
					(size 1.016 1.016)
					(thickness 0.1524)
				)
			)
		)
		(property "Device Type" "CT7343H79"
			(at 0 -11.1252 270)
			(unlocked yes)
			(layer "F.Fab")
			(hide yes)
			(effects
				(font
					(size 1.016 1.016)
					(thickness 0.1524)
				)
			)
		)
		(duplicate_pad_numbers_are_jumpers no)
		(fp_line
			(start -2.286 4.8768)
			(end -2.286 2.032)
			(stroke
				(width 0.1524)
				(type default)
			)
			(layer "F.SilkS")
		)
		(fp_line
			(start 2.286 4.8768)
			(end -2.286 4.8768)
			(stroke
				(width 0.1524)
				(type default)
			)
			(layer "F.SilkS")
		)
		(fp_line
			(start 2.286 2.032)
			(end 2.286 4.8768)
			(stroke
				(width 0.1524)
				(type default)
			)
			(layer "F.SilkS")
		)
		(fp_line
			(start 2.286 -2.032)
			(end 2.286 -4.8768)
			(stroke
				(width 0.1524)
				(type default)
			)
			(layer "F.SilkS")
		)
		(fp_line
			(start 2.1082 -4.699)
			(end -2.1082 -4.699)
			(stroke
				(width 0.508)
				(type default)
			)
			(layer "F.SilkS")
		)
		(fp_line
			(start -2.286 -4.8768)
			(end -2.286 -2.032)
			(stroke
				(width 0.1524)
				(type default)
			)
			(layer "F.SilkS")
		)
		(fp_line
			(start 2.286 -4.8768)
			(end -2.286 -4.8768)
			(stroke
				(width 0.1524)
				(type default)
			)
			(layer "F.SilkS")
		)
		(fp_rect
			(start -2.1463 3.6449)
			(end 2.1463 -3.6449)
			(stroke
				(width 0)
				(type default)
			)
			(fill no)
			(layer "F.CrtYd")
		)
		(fp_poly
			(pts
				(xy -2.54 4.953) (xy -2.54 4.2926) (xy -3.81 4.2926) (xy -3.81 -4.2926) (xy -2.54 -4.2926) (xy -2.54 -4.953)
				(xy 2.54 -4.953) (xy 2.54 -4.2926) (xy 3.81 -4.2926) (xy 3.81 -1.6256) (xy 2.1463 -1.6256) (xy 2.1463 -3.6449)
				(xy -2.1463 -3.6449) (xy -2.1463 3.6449) (xy 2.1463 3.6449) (xy 2.1463 -1.6129) (xy 3.81 -1.6129)
				(xy 3.81 4.2926) (xy 2.54 4.2926) (xy 2.54 4.953)
			)
			(stroke
				(width 0)
				(type default)
			)
			(fill no)
			(layer "F.CrtYd")
		)
		(fp_rect
			(start -2.54 4.953)
			(end 2.54 -4.953)
			(stroke
				(width 0)
				(type default)
			)
			(fill no)
			(layer "F.Fab")
		)
		(fp_rect
			(start -3.81 4.2926)
			(end -2.54 -4.2926)
			(stroke
				(width 0)
				(type default)
			)
			(fill no)
			(layer "F.Fab")
		)
		(fp_rect
			(start 2.54 4.2926)
			(end 3.81 -4.2926)
			(stroke
				(width 0)
				(type default)
			)
			(fill no)
			(layer "F.Fab")
		)
		(pad "1" smd rect
			(at 0 -3.1496 270)
			(size 2.413 2.286)
			(layers "F.Cu" "F.Mask" "F.Paste")
			(net "P12V_A_COMP")
		)
		(pad "2" smd rect
			(at 0 3.1496 270)
			(size 2.413 2.286)
			(layers "F.Cu" "F.Mask" "F.Paste")
			(net "GND")
		)
		(zone
			(layer "F.Cu")
			(hatch none 0.5)
			(connect_pads
				(clearance 0)
			)
			(min_thickness 0.25)
			(keepout
				(tracks allowed)
				(vias not_allowed)
				(pads allowed)
				(copperpour not_allowed)
				(footprints allowed)
			)
			(placement
				(enabled no)
				(sheetname "")
			)
			(fill
				(thermal_gap 0.5)
				(thermal_bridge_width 0.5)
				(island_removal_mode 0)
			)
			(polygon
				(pts
					(xy 215.310466 -16.71828) (xy 215.310466 -13.69568) (xy 218.206066 -13.69568) (xy 218.536266 -13.69568)
					(xy 218.536266 -16.71828) (xy 218.206066 -16.71828)
				)
			)
		)
		(zone
			(layer "F.Cu")
			(hatch none 0.5)
			(connect_pads
				(clearance 0)
			)
			(min_thickness 0.25)
			(keepout
				(tracks allowed)
				(vias not_allowed)
				(pads allowed)
				(copperpour not_allowed)
				(footprints allowed)
			)
			(placement
				(enabled no)
				(sheetname "")
			)
			(fill
				(thermal_gap 0.5)
				(thermal_bridge_width 0.5)
				(island_removal_mode 0)
			)
			(polygon
				(pts
					(xy 221.596966 -13.69568) (xy 224.505266 -13.69568) (xy 224.505266 -16.71828) (xy 221.609666 -16.71828)
					(xy 221.279466 -16.71828) (xy 221.279466 -13.69568)
				)
			)
		)
	)
	(footprint ""
		(layer "F.Cu")
		(at 46.392846 -174.857918)
		(property "Reference" "Q80"
			(at 0 0 0)
			(layer "F.SilkS")
			(hide yes)
			(effects
				(font
					(size 1.27 1.27)
				)
			)
		)
		(property "Value" "AO4407AL-GP"
			(at -3.707384 -1.5367 0)
			(unlocked yes)
			(layer "F.Fab")
			(hide yes)
			(effects
				(font
					(size 1.016 1.016)
					(thickness 0.1524)
				)
			)
		)
		(property "Device Type" "SOIC8H69"
			(at -3.707384 -3.0607 0)
			(unlocked yes)
			(layer "F.Fab")
			(hide yes)
			(effects
				(font
					(size 1.016 1.016)
					(thickness 0.1524)
				)
			)
		)
		(duplicate_pad_numbers_are_jumpers no)
		(fp_line
			(start -2.7432 -1.4224)
			(end -2.7432 1.4224)
			(stroke
				(width 0.1524)
				(type default)
			)
			(layer "F.SilkS")
		)
		(fp_line
			(start -2.7432 1.4224)
			(end -2.6416 1.4224)
			(stroke
				(width 0.1524)
				(type default)
			)
			(layer "F.SilkS")
		)
		(fp_line
			(start -2.7432 1.4224)
			(end 2.1336 1.4224)
			(stroke
				(width 0.1524)
				(type default)
			)
			(layer "F.SilkS")
		)
		(fp_line
			(start -2.7178 -0.508)
			(end -2.1844 -0.0508)
			(stroke
				(width 0.1524)
				(type default)
			)
			(layer "F.SilkS")
		)
		(fp_line
			(start -2.6289 3.4417)
			(end -2.6289 1.4732)
			(stroke
				(width 0.381)
				(type default)
			)
			(layer "F.SilkS")
		)
		(fp_line
			(start -2.1844 -0.0508)
			(end -2.7178 0.508)
			(stroke
				(width 0.1524)
				(type default)
			)
			(layer "F.SilkS")
		)
		(fp_line
			(start 2.1336 -1.4224)
			(end -2.7432 -1.4224)
			(stroke
				(width 0.1524)
				(type default)
			)
			(layer "F.SilkS")
		)
		(fp_line
			(start 2.1336 1.4224)
			(end 2.1336 -1.4224)
			(stroke
				(width 0.1524)
				(type default)
			)
			(layer "F.SilkS")
		)
		(fp_poly
			(pts
				(xy -2.2098 -1.4224) (xy -2.2098 1.4224) (xy 2.2098 1.4224) (xy 2.2098 -1.4224)
			)
			(stroke
				(width 0)
				(type default)
			)
			(fill yes)
			(layer "F.SilkS")
		)
		(fp_rect
			(start -2.450084 2.999994)
			(end 2.450084 -2.999994)
			(stroke
				(width 0)
				(type default)
			)
			(fill no)
			(layer "F.CrtYd")
		)
		(fp_poly
			(pts
				(xy -2.8194 3.6322) (xy -2.8194 -3.6322) (xy 2.8194 -3.6322) (xy 2.8194 1.18364) (xy 2.450084 1.18364)
				(xy 2.450084 -2.999994) (xy -2.450084 -2.999994) (xy -2.450084 2.999994) (xy 2.450084 2.999994)
				(xy 2.450084 1.18618) (xy 2.8194 1.18618) (xy 2.8194 3.6322)
			)
			(stroke
				(width 0)
				(type default)
			)
			(fill no)
			(layer "F.CrtYd")
		)
		(fp_rect
			(start -2.8194 3.6322)
			(end 2.8194 -3.6322)
			(stroke
				(width 0)
				(type default)
			)
			(fill no)
			(layer "F.Fab")
		)
		(pad "1" smd rect
			(at -1.905 2.54)
			(size 0.635 1.651)
			(layers "F.Cu" "F.Mask" "F.Paste")
			(net "P12V_A")
		)
		(pad "2" smd rect
			(at -0.635 2.54)
			(size 0.635 1.651)
			(layers "F.Cu" "F.Mask" "F.Paste")
			(net "P12V_A")
		)
		(pad "3" smd rect
			(at 0.635 2.54)
			(size 0.635 1.651)
			(layers "F.Cu" "F.Mask" "F.Paste")
			(net "P12V_A")
		)
		(pad "4" smd rect
			(at 1.905 2.54)
			(size 0.635 1.651)
			(layers "F.Cu" "F.Mask" "F.Paste")
			(net "SW_HDD_N13")
		)
		(pad "5" smd rect
			(at 1.905 -2.54)
			(size 0.635 1.651)
			(layers "F.Cu" "F.Mask" "F.Paste")
			(net "P12V_HDD13")
		)
		(pad "6" smd rect
			(at 0.635 -2.54)
			(size 0.635 1.651)
			(layers "F.Cu" "F.Mask" "F.Paste")
			(net "P12V_HDD13")
		)
		(pad "7" smd rect
			(at -0.635 -2.54)
			(size 0.635 1.651)
			(layers "F.Cu" "F.Mask" "F.Paste")
			(net "P12V_HDD13")
		)
		(pad "8" smd rect
			(at -1.905 -2.54)
			(size 0.635 1.651)
			(layers "F.Cu" "F.Mask" "F.Paste")
			(net "P12V_HDD13")
		)
	)
	(footprint ""
		(layer "F.Cu")
		(at 287.147 -278.384)
		(property "Reference" "U12"
			(at 0 0 0)
			(layer "F.SilkS")
			(hide yes)
			(effects
				(font
					(size 1.27 1.27)
				)
			)
		)
		(property "Value" "TCA9555PWR-GP"
			(at 0 -6.9342 0)
			(unlocked yes)
			(layer "F.Fab")
			(hide yes)
			(effects
				(font
					(size 1.016 1.016)
					(thickness 0.1524)
				)
			)
		)
		(property "Device Type" "TSOIC24H48"
			(at 0 -8.5852 0)
			(unlocked yes)
			(layer "F.Fab")
			(hide yes)
			(effects
				(font
					(size 1.016 1.016)
					(thickness 0.1524)
				)
			)
		)
		(duplicate_pad_numbers_are_jumpers no)
		(fp_line
			(start -4.2291 -1.397)
			(end 3.81 -1.397)
			(stroke
				(width 0.1524)
				(type default)
			)
			(layer "F.SilkS")
		)
		(fp_line
			(start -4.2291 -0.8001)
			(end -3.429 0)
			(stroke
				(width 0.1524)
				(type default)
			)
			(layer "F.SilkS")
		)
		(fp_line
			(start -4.2291 3.937)
			(end -4.2291 -1.397)
			(stroke
				(width 0.1524)
				(type default)
			)
			(layer "F.SilkS")
		)
		(fp_line
			(start -4.22656 3.81)
			(end -4.2291 1.397)
			(stroke
				(width 0.508)
				(type default)
			)
			(layer "F.SilkS")
		)
		(fp_line
			(start -3.429 0)
			(end -4.2291 0.8001)
			(stroke
				(width 0.1524)
				(type default)
			)
			(layer "F.SilkS")
		)
		(fp_line
			(start 3.81 -1.397)
			(end 3.81 1.397)
			(stroke
				(width 0.1524)
				(type default)
			)
			(layer "F.SilkS")
		)
		(fp_line
			(start 3.81 1.397)
			(end -4.2291 1.397)
			(stroke
				(width 0.1524)
				(type default)
			)
			(layer "F.SilkS")
		)
		(fp_poly
			(pts
				(xy -3.90652 -1.8542) (xy 3.90652 -1.8542) (xy 3.90652 1.8542) (xy -3.90652 1.8542)
			)
			(stroke
				(width 0)
				(type default)
			)
			(fill yes)
			(layer "F.SilkS")
		)
		(fp_poly
			(pts
				(xy -4.2164 3.81) (xy 4.2164 3.81) (xy 4.22656 -3.81) (xy -4.2164 -3.81)
			)
			(stroke
				(width 0)
				(type default)
			)
			(fill no)
			(layer "F.CrtYd")
		)
		(fp_poly
			(pts
				(xy -4.22656 -3.81) (xy 4.22656 -3.81) (xy 4.22656 3.81) (xy -4.22656 3.81)
			)
			(stroke
				(width 0)
				(type default)
			)
			(fill no)
			(layer "F.Fab")
		)
		(pad "1" smd rect
			(at -3.57632 2.8194)
			(size 0.3556 1.524)
			(layers "F.Cu" "F.Mask" "F.Paste")
			(net "IO_EXP2_HDD_FAULT_INT_N")
		)
		(pad "2" smd rect
			(at -2.92608 2.8194)
			(size 0.3556 1.524)
			(layers "F.Cu" "F.Mask" "F.Paste")
			(net "IO_EXP2_HDD_FAULT_A1")
		)
		(pad "3" smd rect
			(at -2.27584 2.8194)
			(size 0.3556 1.524)
			(layers "F.Cu" "F.Mask" "F.Paste")
			(net "IO_EXP2_HDD_FAULT_A2")
		)
		(pad "4" smd rect
			(at -1.6256 2.8194)
			(size 0.3556 1.524)
			(layers "F.Cu" "F.Mask" "F.Paste")
			(net "DRIVE_A_24_FLT_LED")
		)
		(pad "5" smd rect
			(at -0.97536 2.8194)
			(size 0.3556 1.524)
			(layers "F.Cu" "F.Mask" "F.Paste")
			(net "DRIVE_A_25_FLT_LED")
		)
		(pad "6" smd rect
			(at -0.32512 2.8194)
			(size 0.3556 1.524)
			(layers "F.Cu" "F.Mask" "F.Paste")
			(net "DRIVE_A_26_FLT_LED")
		)
		(pad "7" smd rect
			(at 0.32512 2.8194)
			(size 0.3556 1.524)
			(layers "F.Cu" "F.Mask" "F.Paste")
			(net "DRIVE_A_27_FLT_LED")
		)
		(pad "8" smd rect
			(at 0.97536 2.8194)
			(size 0.3556 1.524)
			(layers "F.Cu" "F.Mask" "F.Paste")
			(net "DRIVE_A_28_FLT_LED")
		)
		(pad "9" smd rect
			(at 1.6256 2.8194)
			(size 0.3556 1.524)
			(layers "F.Cu" "F.Mask" "F.Paste")
			(net "DRIVE_A_29_FLT_LED")
		)
		(pad "10" smd rect
			(at 2.27584 2.8194)
			(size 0.3556 1.524)
			(layers "F.Cu" "F.Mask" "F.Paste")
			(net "DRIVE_A_30_FLT_LED")
		)
		(pad "11" smd rect
			(at 2.92608 2.8194)
			(size 0.3556 1.524)
			(layers "F.Cu" "F.Mask" "F.Paste")
			(net "DRIVE_A_31_FLT_LED")
		)
		(pad "12" smd rect
			(at 3.57632 2.8194)
			(size 0.3556 1.524)
			(layers "F.Cu" "F.Mask" "F.Paste")
			(net "GND")
		)
		(pad "13" smd rect
			(at 3.57632 -2.8194)
			(size 0.3556 1.524)
			(layers "F.Cu" "F.Mask" "F.Paste")
			(net "DRIVE_A_32_FLT_LED")
		)
		(pad "14" smd rect
			(at 2.92608 -2.8194)
			(size 0.3556 1.524)
			(layers "F.Cu" "F.Mask" "F.Paste")
			(net "DRIVE_A_33_FLT_LED")
		)
		(pad "15" smd rect
			(at 2.27584 -2.8194)
			(size 0.3556 1.524)
			(layers "F.Cu" "F.Mask" "F.Paste")
			(net "DRIVE_A_34_FLT_LED")
		)
		(pad "16" smd rect
			(at 1.6256 -2.8194)
			(size 0.3556 1.524)
			(layers "F.Cu" "F.Mask" "F.Paste")
			(net "DRIVE_A_35_FLT_LED")
		)
		(pad "17" smd rect
			(at 0.97536 -2.8194)
			(size 0.3556 1.524)
			(layers "F.Cu" "F.Mask" "F.Paste")
			(net "Net_275")
		)
		(pad "18" smd rect
			(at 0.32512 -2.8194)
			(size 0.3556 1.524)
			(layers "F.Cu" "F.Mask" "F.Paste")
			(net "Net_274")
		)
		(pad "19" smd rect
			(at -0.32512 -2.8194)
			(size 0.3556 1.524)
			(layers "F.Cu" "F.Mask" "F.Paste")
			(net "Net_273")
		)
		(pad "20" smd rect
			(at -0.97536 -2.8194)
			(size 0.3556 1.524)
			(layers "F.Cu" "F.Mask" "F.Paste")
			(net "Net_272")
		)
		(pad "21" smd rect
			(at -1.6256 -2.8194)
			(size 0.3556 1.524)
			(layers "F.Cu" "F.Mask" "F.Paste")
			(net "IO_EXP2_HDD_FAULT_A0")
		)
		(pad "22" smd rect
			(at -2.27584 -2.8194)
			(size 0.3556 1.524)
			(layers "F.Cu" "F.Mask" "F.Paste")
			(net "IO_EXP2_LED_SCL")
		)
		(pad "23" smd rect
			(at -2.92608 -2.8194)
			(size 0.3556 1.524)
			(layers "F.Cu" "F.Mask" "F.Paste")
			(net "IO_EXP2_LED_SDA")
		)
		(pad "24" smd rect
			(at -3.57632 -2.8194)
			(size 0.3556 1.524)
			(layers "F.Cu" "F.Mask" "F.Paste")
			(net "P3V3_STBY_A")
		)
	)
	(footprint ""
		(layer "F.Cu")
		(at 50.456846 -294.683942 90)
		(property "Reference" "R154"
			(at 0 0 90)
			(layer "F.SilkS")
			(hide yes)
			(effects
				(font
					(size 1.27 1.27)
				)
			)
		)
		(property "Value" "2R6F-GP"
			(at -0.0508 -4.8514 90)
			(unlocked yes)
			(layer "F.Fab")
			(hide yes)
			(effects
				(font
					(size 1.016 1.016)
					(thickness 0.1524)
				)
			)
		)
		(property "Device Type" "R1206H26"
			(at 0 -6.3754 90)
			(unlocked yes)
			(layer "F.Fab")
			(hide yes)
			(effects
				(font
					(size 1.016 1.016)
					(thickness 0.1524)
				)
			)
		)
		(duplicate_pad_numbers_are_jumpers no)
		(fp_line
			(start 1.016 -2.2352)
			(end 1.016 2.2352)
			(stroke
				(width 0.1524)
				(type default)
			)
			(layer "F.SilkS")
		)
		(fp_line
			(start -1.016 -2.2352)
			(end 1.016 -2.2352)
			(stroke
				(width 0.1524)
				(type default)
			)
			(layer "F.SilkS")
		)
		(fp_line
			(start 1.016 2.2352)
			(end -1.016 2.2352)
			(stroke
				(width 0.1524)
				(type default)
			)
			(layer "F.SilkS")
		)
		(fp_line
			(start -1.016 2.2352)
			(end -1.016 -2.2352)
			(stroke
				(width 0.1524)
				(type default)
			)
			(layer "F.SilkS")
		)
		(fp_rect
			(start -1.0922 2.3114)
			(end 1.0922 -2.3114)
			(stroke
				(width 0)
				(type default)
			)
			(fill no)
			(layer "F.CrtYd")
		)
		(fp_poly
			(pts
				(xy -1.0922 -2.3114) (xy 1.0922 -2.3114) (xy 1.0922 2.3114) (xy -1.0922 2.3114)
			)
			(stroke
				(width 0)
				(type default)
			)
			(fill no)
			(layer "F.Fab")
		)
		(pad "1" smd rect
			(at 0 -1.397 90)
			(size 1.651 1.27)
			(layers "F.Cu" "F.Mask" "F.Paste")
			(net "P12V_HDD1")
		)
		(pad "2" smd rect
			(at 0 1.397 90)
			(size 1.651 1.27)
			(layers "F.Cu" "F.Mask" "F.Paste")
			(net "12V_PRE_1")
		)
	)
	(footprint ""
		(layer "F.Cu")
		(at 272.542 -307.304948 180)
		(property "Reference" "VIA61"
			(at 0 0 180)
			(layer "F.SilkS")
			(hide yes)
			(effects
				(font
					(size 1.27 1.27)
				)
			)
		)
		(property "Value" "100OHM-8L-1D6MM-L18L16-GP"
			(at -3.7211 -4.5085 180)
			(unlocked yes)
			(layer "F.Fab")
			(hide yes)
			(effects
				(font
					(size 1.016 1.016)
					(thickness 0.1524)
				)
			)
		)
		(property "Device Type" "VIA-PCIE-4P-394076"
			(at -3.7211 -6.0325 180)
			(unlocked yes)
			(layer "F.Fab")
			(hide yes)
			(effects
				(font
					(size 1.016 1.016)
					(thickness 0.1524)
				)
			)
		)
		(duplicate_pad_numbers_are_jumpers no)
		(fp_rect
			(start -1.9685 0.381)
			(end 1.9685 -0.381)
			(stroke
				(width 0)
				(type default)
			)
			(fill no)
			(layer "F.CrtYd")
		)
		(fp_rect
			(start -1.9685 0.381)
			(end 1.9685 -0.381)
			(stroke
				(width 0)
				(type default)
			)
			(fill no)
			(layer "F.Fab")
		)
		(pad "1" thru_hole circle
			(at -1.5875 0 180)
			(size 0.508 0.508)
			(drill 0.254)
			(layers "*.Cu" "*.Mask")
			(remove_unused_layers no)
			(net "GND")
			(clearance 0.127)
			(thermal_gap 0.127)
		)
		(pad "2" thru_hole circle
			(at -0.5715 0 180)
			(size 0.508 0.508)
			(drill 0.254)
			(layers "*.Cu" "*.Mask")
			(remove_unused_layers no)
			(net "PHY_SCC_A_TO_DRV_A_29_DP")
			(clearance 0.127)
			(thermal_gap 0.127)
		)
		(pad "3" thru_hole circle
			(at 0.5715 0 180)
			(size 0.508 0.508)
			(drill 0.254)
			(layers "*.Cu" "*.Mask")
			(remove_unused_layers no)
			(net "PHY_SCC_A_TO_DRV_A_29_DN")
			(clearance 0.127)
			(thermal_gap 0.127)
		)
		(pad "4" thru_hole circle
			(at 1.5875 0 180)
			(size 0.508 0.508)
			(drill 0.254)
			(layers "*.Cu" "*.Mask")
			(remove_unused_layers no)
			(net "GND")
			(clearance 0.127)
			(thermal_gap 0.127)
		)
	)
)
